(kicad_pcb
	(version 20260206)
	(generator "pcbnew")
	(generator_version "10.0")
	(general
		(thickness 1.6)
		(legacy_teardrops no)
	)
	(paper "A4")
	(title_block
		(title "dpb — 14545-sa.0730WZS0815.brd")
		(comment 1 "Honey Badger (Wiwynn) / footprints 429-433 of 1066")
	)
	(layers
		(0 "F.Cu" signal "TOP")
		(4 "In1.Cu" signal "L2GND")
		(6 "In2.Cu" signal "L3")
		(8 "In3.Cu" signal "L4VCC")
		(10 "In4.Cu" signal "L5VCC")
		(12 "In5.Cu" signal "L6")
		(14 "In6.Cu" signal "L7GND")
		(2 "B.Cu" signal "BOTTOM")
		(9 "F.Adhes" user "F.Adhesive")
		(11 "B.Adhes" user "B.Adhesive")
		(13 "F.Paste" user "Package Geometry/Pastemask Top")
		(15 "B.Paste" user "Package Geometry/Pastemask Bottom")
		(5 "F.SilkS" user "Ref Des/Silkscreen Top")
		(7 "B.SilkS" user "Ref Des/Silkscreen Bottom")
		(1 "F.Mask" user "Board Geometry/Soldermask Top")
		(3 "B.Mask" user "Board Geometry/Soldermask Bottom")
		(17 "Dwgs.User" user "User.Drawings")
		(19 "Cmts.User" user "User.Comments")
		(21 "Eco1.User" user "User.Eco1")
		(23 "Eco2.User" user "User.Eco2")
		(25 "Edge.Cuts" user "Board Geometry/Outline")
		(27 "Margin" user)
		(31 "F.CrtYd" user "Package Geometry/Place Bound Top")
		(29 "B.CrtYd" user "Package Geometry/Place Bound Bottom")
		(35 "F.Fab" user "Ref Des/Assembly Top")
		(33 "B.Fab" user "Ref Des/Assembly Bottom")
	)
	(footprint ""
		(layer "F.Cu")
		(at 233.247946 -143.9926 90)
		(property "Reference" "Q37"
			(at 0 0 90)
			(layer "F.SilkS")
			(hide yes)
			(effects
				(font
					(size 1.27 1.27)
				)
			)
		)
		(property "Value" "PMBS3904-1-GP"
			(at 0 -9.0932 90)
			(unlocked yes)
			(layer "F.Fab")
			(hide yes)
			(effects
				(font
					(size 1.016 1.016)
					(thickness 0.1524)
				)
			)
		)
		(property "Device Type" "SOT-23-10H44"
			(at 0 -10.6172 90)
			(unlocked yes)
			(layer "F.Fab")
			(hide yes)
			(effects
				(font
					(size 1.016 1.016)
					(thickness 0.1524)
				)
			)
		)
		(duplicate_pad_numbers_are_jumpers no)
		(fp_line
			(start 1.651 -1.778)
			(end -1.651 -1.778)
			(stroke
				(width 0.1524)
				(type default)
			)
			(layer "F.SilkS")
		)
		(fp_line
			(start -1.651 -1.778)
			(end -1.651 1.778)
			(stroke
				(width 0.1524)
				(type default)
			)
			(layer "F.SilkS")
		)
		(fp_line
			(start 1.651 1.778)
			(end 1.651 -1.778)
			(stroke
				(width 0.1524)
				(type default)
			)
			(layer "F.SilkS")
		)
		(fp_line
			(start -1.651 1.778)
			(end 1.651 1.778)
			(stroke
				(width 0.1524)
				(type default)
			)
			(layer "F.SilkS")
		)
		(fp_line
			(start -0.9906 1.86309)
			(end -0.701294 2.15265)
			(stroke
				(width 0.0127)
				(type default)
			)
			(layer "F.SilkS")
		)
		(fp_line
			(start -0.994156 1.8669)
			(end -0.987044 1.8669)
			(stroke
				(width 0.0127)
				(type default)
			)
			(layer "F.SilkS")
		)
		(fp_line
			(start -1.003808 1.876552)
			(end -0.977646 1.876552)
			(stroke
				(width 0.0127)
				(type default)
			)
			(layer "F.SilkS")
		)
		(fp_line
			(start -0.635 1.8796)
			(end -1.7526 1.8796)
			(stroke
				(width 0.3302)
				(type default)
			)
			(layer "F.SilkS")
		)
		(fp_line
			(start -1.7526 1.8796)
			(end -1.7526 0.9906)
			(stroke
				(width 0.3302)
				(type default)
			)
			(layer "F.SilkS")
		)
		(fp_line
			(start -1.013206 1.88595)
			(end -0.967994 1.88595)
			(stroke
				(width 0.0127)
				(type default)
			)
			(layer "F.SilkS")
		)
		(fp_line
			(start -1.022858 1.895602)
			(end -0.958596 1.895602)
			(stroke
				(width 0.0127)
				(type default)
			)
			(layer "F.SilkS")
		)
		(fp_line
			(start -1.032256 1.905)
			(end -0.948944 1.905)
			(stroke
				(width 0.0127)
				(type default)
			)
			(layer "F.SilkS")
		)
		(fp_line
			(start -1.041908 1.914652)
			(end -0.939546 1.914652)
			(stroke
				(width 0.0127)
				(type default)
			)
			(layer "F.SilkS")
		)
		(fp_line
			(start -1.051306 1.92405)
			(end -0.929894 1.92405)
			(stroke
				(width 0.0127)
				(type default)
			)
			(layer "F.SilkS")
		)
		(fp_line
			(start -1.060958 1.933702)
			(end -0.920496 1.933702)
			(stroke
				(width 0.0127)
				(type default)
			)
			(layer "F.SilkS")
		)
		(fp_line
			(start -1.070356 1.9431)
			(end -0.910844 1.9431)
			(stroke
				(width 0.0127)
				(type default)
			)
			(layer "F.SilkS")
		)
		(fp_line
			(start -1.080008 1.952752)
			(end -0.901446 1.952752)
			(stroke
				(width 0.0127)
				(type default)
			)
			(layer "F.SilkS")
		)
		(fp_line
			(start -1.089406 1.96215)
			(end -0.891794 1.96215)
			(stroke
				(width 0.0127)
				(type default)
			)
			(layer "F.SilkS")
		)
		(fp_line
			(start -1.099058 1.971802)
			(end -0.882396 1.971802)
			(stroke
				(width 0.0127)
				(type default)
			)
			(layer "F.SilkS")
		)
		(fp_line
			(start -1.108456 1.9812)
			(end -0.872744 1.9812)
			(stroke
				(width 0.0127)
				(type default)
			)
			(layer "F.SilkS")
		)
		(fp_line
			(start -1.118108 1.990852)
			(end -0.863346 1.990852)
			(stroke
				(width 0.0127)
				(type default)
			)
			(layer "F.SilkS")
		)
		(fp_line
			(start -1.127506 2.00025)
			(end -0.853694 2.00025)
			(stroke
				(width 0.0127)
				(type default)
			)
			(layer "F.SilkS")
		)
		(fp_line
			(start -1.137158 2.009902)
			(end -0.844296 2.009902)
			(stroke
				(width 0.0127)
				(type default)
			)
			(layer "F.SilkS")
		)
		(fp_line
			(start -1.146556 2.0193)
			(end -0.834644 2.0193)
			(stroke
				(width 0.0127)
				(type default)
			)
			(layer "F.SilkS")
		)
		(fp_line
			(start -1.156208 2.028952)
			(end -0.825246 2.028952)
			(stroke
				(width 0.0127)
				(type default)
			)
			(layer "F.SilkS")
		)
		(fp_line
			(start -1.165606 2.03835)
			(end -0.815594 2.03835)
			(stroke
				(width 0.0127)
				(type default)
			)
			(layer "F.SilkS")
		)
		(fp_line
			(start -1.175258 2.048002)
			(end -0.806196 2.048002)
			(stroke
				(width 0.0127)
				(type default)
			)
			(layer "F.SilkS")
		)
		(fp_line
			(start -1.184656 2.0574)
			(end -0.796544 2.0574)
			(stroke
				(width 0.0127)
				(type default)
			)
			(layer "F.SilkS")
		)
		(fp_line
			(start -1.194308 2.067052)
			(end -0.787146 2.067052)
			(stroke
				(width 0.0127)
				(type default)
			)
			(layer "F.SilkS")
		)
		(fp_line
			(start -1.203706 2.07645)
			(end -0.777494 2.07645)
			(stroke
				(width 0.0127)
				(type default)
			)
			(layer "F.SilkS")
		)
		(fp_line
			(start -1.213358 2.086102)
			(end -0.768096 2.086102)
			(stroke
				(width 0.0127)
				(type default)
			)
			(layer "F.SilkS")
		)
		(fp_line
			(start -1.222756 2.0955)
			(end -0.758444 2.0955)
			(stroke
				(width 0.0127)
				(type default)
			)
			(layer "F.SilkS")
		)
		(fp_line
			(start -1.232408 2.105152)
			(end -0.749046 2.105152)
			(stroke
				(width 0.0127)
				(type default)
			)
			(layer "F.SilkS")
		)
		(fp_line
			(start -1.241806 2.11455)
			(end -0.739394 2.11455)
			(stroke
				(width 0.0127)
				(type default)
			)
			(layer "F.SilkS")
		)
		(fp_line
			(start -1.251458 2.124202)
			(end -0.729996 2.124202)
			(stroke
				(width 0.0127)
				(type default)
			)
			(layer "F.SilkS")
		)
		(fp_line
			(start -1.260856 2.1336)
			(end -0.720344 2.1336)
			(stroke
				(width 0.0127)
				(type default)
			)
			(layer "F.SilkS")
		)
		(fp_line
			(start -0.719074 2.145538)
			(end -1.265936 2.14122)
			(stroke
				(width 0.0127)
				(type default)
			)
			(layer "F.SilkS")
		)
		(fp_line
			(start -1.279398 2.152142)
			(end -0.9906 1.86309)
			(stroke
				(width 0.0127)
				(type default)
			)
			(layer "F.SilkS")
		)
		(fp_line
			(start -0.71628 2.15265)
			(end -1.26492 2.15265)
			(stroke
				(width 0.0127)
				(type default)
			)
			(layer "F.SilkS")
		)
		(fp_line
			(start -1.279144 2.15265)
			(end -0.701294 2.15265)
			(stroke
				(width 0.0127)
				(type default)
			)
			(layer "F.SilkS")
		)
		(fp_poly
			(pts
				(xy -1.285748 2.159) (xy -1.285748 1.8796) (xy -1.778 1.8796) (xy -1.778 -1.8796) (xy 1.778 -1.8796)
				(xy 1.778 1.8796) (xy -0.694944 1.8796) (xy -0.694944 2.159)
			)
			(stroke
				(width 0)
				(type default)
			)
			(fill no)
			(layer "F.CrtYd")
		)
		(fp_poly
			(pts
				(xy -1.285748 2.159) (xy -1.285748 1.8796) (xy -1.778 1.8796) (xy -1.778 -1.8796) (xy 1.778 -1.8796)
				(xy 1.778 1.8796) (xy -0.694944 1.8796) (xy -0.694944 2.159)
			)
			(stroke
				(width 0)
				(type default)
			)
			(fill no)
			(layer "F.Fab")
		)
		(pad "1" smd rect
			(at -0.98425 0.9525 90)
			(size 0.762 1.143)
			(layers "F.Cu" "F.Mask" "F.Paste")
			(net "FLT_HDD3_B")
		)
		(pad "2" smd rect
			(at 0.98425 0.9525 90)
			(size 0.762 1.143)
			(layers "F.Cu" "F.Mask" "F.Paste")
			(net "GND")
		)
		(pad "3" smd rect
			(at 0 -0.9525 90)
			(size 0.762 1.143)
			(layers "F.Cu" "F.Mask" "F.Paste")
			(net "DRIVE_ACT_3")
		)
	)
	(footprint ""
		(layer "F.Cu")
		(at 14.478 -182.753 90)
		(property "Reference" "TC2"
			(at 0 0 90)
			(layer "F.SilkS")
			(hide yes)
			(effects
				(font
					(size 1.27 1.27)
				)
			)
		)
		(property "Value" "ST15U25VDM-1-GP"
			(at 0 -9.6012 90)
			(unlocked yes)
			(layer "F.Fab")
			(hide yes)
			(effects
				(font
					(size 1.016 1.016)
					(thickness 0.1524)
				)
			)
		)
		(property "Device Type" "CT7343H79"
			(at 0 -11.1252 90)
			(unlocked yes)
			(layer "F.Fab")
			(hide yes)
			(effects
				(font
					(size 1.016 1.016)
					(thickness 0.1524)
				)
			)
		)
		(duplicate_pad_numbers_are_jumpers no)
		(fp_line
			(start 2.286 -4.8768)
			(end -2.286 -4.8768)
			(stroke
				(width 0.1524)
				(type default)
			)
			(layer "F.SilkS")
		)
		(fp_line
			(start -2.286 -4.8768)
			(end -2.286 -2.032)
			(stroke
				(width 0.1524)
				(type default)
			)
			(layer "F.SilkS")
		)
		(fp_line
			(start 2.1082 -4.699)
			(end -2.1082 -4.699)
			(stroke
				(width 0.508)
				(type default)
			)
			(layer "F.SilkS")
		)
		(fp_line
			(start 2.286 -2.032)
			(end 2.286 -4.8768)
			(stroke
				(width 0.1524)
				(type default)
			)
			(layer "F.SilkS")
		)
		(fp_line
			(start 2.286 2.032)
			(end 2.286 4.8768)
			(stroke
				(width 0.1524)
				(type default)
			)
			(layer "F.SilkS")
		)
		(fp_line
			(start 2.286 4.8768)
			(end -2.286 4.8768)
			(stroke
				(width 0.1524)
				(type default)
			)
			(layer "F.SilkS")
		)
		(fp_line
			(start -2.286 4.8768)
			(end -2.286 2.032)
			(stroke
				(width 0.1524)
				(type default)
			)
			(layer "F.SilkS")
		)
		(fp_rect
			(start -2.1463 3.6449)
			(end 2.1463 -3.6449)
			(stroke
				(width 0)
				(type default)
			)
			(fill no)
			(layer "F.CrtYd")
		)
		(fp_poly
			(pts
				(xy -2.54 4.953) (xy -2.54 4.2926) (xy -3.81 4.2926) (xy -3.81 -4.2926) (xy -2.54 -4.2926) (xy -2.54 -4.953)
				(xy 2.54 -4.953) (xy 2.54 -4.2926) (xy 3.81 -4.2926) (xy 3.81 -1.6256) (xy 2.1463 -1.6256) (xy 2.1463 -3.6449)
				(xy -2.1463 -3.6449) (xy -2.1463 3.6449) (xy 2.1463 3.6449) (xy 2.1463 -1.6129) (xy 3.81 -1.6129)
				(xy 3.81 4.2926) (xy 2.54 4.2926) (xy 2.54 4.953)
			)
			(stroke
				(width 0)
				(type default)
			)
			(fill no)
			(layer "F.CrtYd")
		)
		(fp_rect
			(start 2.54 4.2926)
			(end 3.81 -4.2926)
			(stroke
				(width 0)
				(type default)
			)
			(fill no)
			(layer "F.Fab")
		)
		(fp_rect
			(start -3.81 4.2926)
			(end -2.54 -4.2926)
			(stroke
				(width 0)
				(type default)
			)
			(fill no)
			(layer "F.Fab")
		)
		(fp_rect
			(start -2.54 4.953)
			(end 2.54 -4.953)
			(stroke
				(width 0)
				(type default)
			)
			(fill no)
			(layer "F.Fab")
		)
		(pad "1" smd rect
			(at 0 -3.1496 90)
			(size 2.413 2.286)
			(layers "F.Cu" "F.Mask" "F.Paste")
			(net "P12V")
		)
		(pad "2" smd rect
			(at 0 3.1496 90)
			(size 2.413 2.286)
			(layers "F.Cu" "F.Mask" "F.Paste")
			(net "GND")
		)
		(zone
			(layer "F.Cu")
			(hatch none 0.5)
			(connect_pads
				(clearance 0)
			)
			(min_thickness 0.25)
			(keepout
				(tracks allowed)
				(vias not_allowed)
				(pads allowed)
				(copperpour not_allowed)
				(footprints allowed)
			)
			(placement
				(enabled no)
				(sheetname "")
			)
			(fill
				(thermal_gap 0.5)
				(thermal_bridge_width 0.5)
				(island_removal_mode 0)
			)
			(polygon
				(pts
					(xy 12.7889 -184.2643) (xy 9.8806 -184.2643) (xy 9.8806 -181.2417) (xy 12.7762 -181.2417) (xy 13.1064 -181.2417)
					(xy 13.1064 -184.2643)
				)
			)
		)
		(zone
			(layer "F.Cu")
			(hatch none 0.5)
			(connect_pads
				(clearance 0)
			)
			(min_thickness 0.25)
			(keepout
				(tracks allowed)
				(vias not_allowed)
				(pads allowed)
				(copperpour not_allowed)
				(footprints allowed)
			)
			(placement
				(enabled no)
				(sheetname "")
			)
			(fill
				(thermal_gap 0.5)
				(thermal_bridge_width 0.5)
				(island_removal_mode 0)
			)
			(polygon
				(pts
					(xy 19.0754 -181.2417) (xy 19.0754 -184.2643) (xy 16.1798 -184.2643) (xy 15.8496 -184.2643) (xy 15.8496 -181.2417)
					(xy 16.1798 -181.2417)
				)
			)
		)
	)
	(footprint ""
		(layer "F.Cu")
		(at 26.161746 -7.3787)
		(property "Reference" "TP39"
			(at 0 0 0)
			(layer "F.SilkS")
			(hide yes)
			(effects
				(font
					(size 1.27 1.27)
				)
			)
		)
		(property "Value" "TPAD32-GP"
			(at 0 -3.166364 0)
			(unlocked yes)
			(layer "F.Fab")
			(hide yes)
			(effects
				(font
					(size 1.016 1.016)
					(thickness 0.1524)
				)
			)
		)
		(property "Device Type" "TPAD32"
			(at 0 -4.690618 0)
			(unlocked yes)
			(layer "F.Fab")
			(hide yes)
			(effects
				(font
					(size 1.016 1.016)
					(thickness 0.1524)
				)
			)
		)
		(duplicate_pad_numbers_are_jumpers no)
		(fp_poly
			(pts
				(arc
					(start 0.4064 0)
					(mid -0.4064 0)
					(end 0.4064 0)
				)
			)
			(stroke
				(width 0)
				(type default)
			)
			(fill no)
			(layer "F.CrtYd")
		)
		(fp_poly
			(pts
				(arc
					(start 0.7112 0)
					(mid -0.7112 0)
					(end 0.7112 0)
				)
			)
			(stroke
				(width 0)
				(type default)
			)
			(fill no)
			(layer "F.Fab")
		)
		(pad "1" smd circle
			(at 0 0)
			(size 0.8128 0.8128)
			(layers "F.Cu" "F.Mask" "F.Paste")
			(net "ACT_HDD14")
		)
	)
	(footprint ""
		(layer "F.Cu")
		(at 83.692746 -394.6017 -90)
		(property "Reference" "R449"
			(at 0 0 270)
			(layer "F.SilkS")
			(hide yes)
			(effects
				(font
					(size 1.27 1.27)
				)
			)
		)
		(property "Value" "4K7R2J-2-GP"
			(at 0.064008 -3.993896 270)
			(unlocked yes)
			(layer "F.Fab")
			(hide yes)
			(effects
				(font
					(size 1.016 1.016)
					(thickness 0.1524)
				)
			)
		)
		(property "Device Type" "R402H16"
			(at 0.064008 -5.517896 270)
			(unlocked yes)
			(layer "F.Fab")
			(hide yes)
			(effects
				(font
					(size 1.016 1.016)
					(thickness 0.1524)
				)
			)
		)
		(duplicate_pad_numbers_are_jumpers no)
		(fp_line
			(start -0.508 -0.9398)
			(end -0.508 0.9398)
			(stroke
				(width 0.1524)
				(type default)
			)
			(layer "F.SilkS")
		)
		(fp_line
			(start 0.508 -0.9398)
			(end -0.508 -0.9398)
			(stroke
				(width 0.1524)
				(type default)
			)
			(layer "F.SilkS")
		)
		(fp_rect
			(start -0.508 0.9398)
			(end 0.508 -0.9398)
			(stroke
				(width 0)
				(type default)
			)
			(fill no)
			(layer "F.CrtYd")
		)
		(fp_rect
			(start -0.508 0.9398)
			(end 0.508 -0.9398)
			(stroke
				(width 0)
				(type default)
			)
			(fill no)
			(layer "F.Fab")
		)
		(pad "1" smd custom
			(at 0 -0.4445 270)
			(size 0.1397 0.1397)
			(layers "F.Cu" "F.Mask" "F.Paste")
			(net "P3V3")
			(options
				(clearance outline)
				(anchor circle)
			)
			(primitives
				(gr_poly
					(pts
						(arc
							(start -0.1778 -0.2794)
							(mid -0.249642 -0.249642)
							(end -0.2794 -0.1778)
						)
						(arc
							(start -0.2794 0.1778)
							(mid -0.249642 0.249642)
							(end -0.1778 0.2794)
						)
						(arc
							(start 0.1778 0.2794)
							(mid 0.249642 0.249642)
							(end 0.2794 0.1778)
						)
						(arc
							(start 0.2794 -0.1778)
							(mid 0.249642 -0.249642)
							(end 0.1778 -0.2794)
						)
					)
					(width 0)
					(fill yes)
				)
			)
		)
		(pad "2" smd custom
			(at 0 0.4445 270)
			(size 0.1397 0.1397)
			(layers "F.Cu" "F.Mask" "F.Paste")
			(net "SAS_EXP_B_PWR6")
			(options
				(clearance outline)
				(anchor circle)
			)
			(primitives
				(gr_poly
					(pts
						(arc
							(start -0.1778 -0.2794)
							(mid -0.249642 -0.249642)
							(end -0.2794 -0.1778)
						)
						(arc
							(start -0.2794 0.1778)
							(mid -0.249642 0.249642)
							(end -0.1778 0.2794)
						)
						(arc
							(start 0.1778 0.2794)
							(mid 0.249642 0.249642)
							(end 0.2794 0.1778)
						)
						(arc
							(start 0.2794 -0.1778)
							(mid 0.249642 -0.249642)
							(end 0.1778 -0.2794)
						)
					)
					(width 0)
					(fill yes)
				)
			)
		)
	)
	(footprint ""
		(layer "F.Cu")
		(at 102.234746 -12.9667 90)
		(property "Reference" "R309"
			(at 0 0 90)
			(layer "F.SilkS")
			(hide yes)
			(effects
				(font
					(size 1.27 1.27)
				)
			)
		)
		(property "Value" "0R2J-2-GP"
			(at 0.064008 -3.993896 90)
			(unlocked yes)
			(layer "F.Fab")
			(hide yes)
			(effects
				(font
					(size 1.016 1.016)
					(thickness 0.1524)
				)
			)
		)
		(property "Device Type" "R402H16"
			(at 0.064008 -5.517896 90)
			(unlocked yes)
			(layer "F.Fab")
			(hide yes)
			(effects
				(font
					(size 1.016 1.016)
					(thickness 0.1524)
				)
			)
		)
		(duplicate_pad_numbers_are_jumpers no)
		(fp_line
			(start 0.508 -0.9398)
			(end -0.508 -0.9398)
			(stroke
				(width 0.1524)
				(type default)
			)
			(layer "F.SilkS")
		)
		(fp_line
			(start -0.508 -0.9398)
			(end -0.508 0.9398)
			(stroke
				(width 0.1524)
				(type default)
			)
			(layer "F.SilkS")
		)
		(fp_rect
			(start -0.508 0.9398)
			(end 0.508 -0.9398)
			(stroke
				(width 0)
				(type default)
			)
			(fill no)
			(layer "F.CrtYd")
		)
		(fp_rect
			(start -0.508 0.9398)
			(end 0.508 -0.9398)
			(stroke
				(width 0)
				(type default)
			)
			(fill no)
			(layer "F.Fab")
		)
		(pad "1" smd custom
			(at 0 -0.4445 90)
			(size 0.1397 0.1397)
			(layers "F.Cu" "F.Mask" "F.Paste")
			(net "DRIVE_PWR14")
			(options
				(clearance outline)
				(anchor circle)
			)
			(primitives
				(gr_poly
					(pts
						(arc
							(start -0.1778 -0.2794)
							(mid -0.249642 -0.249642)
							(end -0.2794 -0.1778)
						)
						(arc
							(start -0.2794 0.1778)
							(mid -0.249642 0.249642)
							(end -0.1778 0.2794)
						)
						(arc
							(start 0.1778 0.2794)
							(mid 0.249642 0.249642)
							(end 0.2794 0.1778)
						)
						(arc
							(start 0.2794 -0.1778)
							(mid 0.249642 -0.249642)
							(end 0.1778 -0.2794)
						)
					)
					(width 0)
					(fill yes)
				)
			)
		)
		(pad "2" smd custom
			(at 0 0.4445 90)
			(size 0.1397 0.1397)
			(layers "F.Cu" "F.Mask" "F.Paste")
			(net "SW_PWR_HDD14")
			(options
				(clearance outline)
				(anchor circle)
			)
			(primitives
				(gr_poly
					(pts
						(arc
							(start -0.1778 -0.2794)
							(mid -0.249642 -0.249642)
							(end -0.2794 -0.1778)
						)
						(arc
							(start -0.2794 0.1778)
							(mid -0.249642 0.249642)
							(end -0.1778 0.2794)
						)
						(arc
							(start 0.1778 0.2794)
							(mid 0.249642 0.249642)
							(end 0.2794 0.1778)
						)
						(arc
							(start 0.2794 -0.1778)
							(mid 0.249642 -0.249642)
							(end 0.1778 -0.2794)
						)
					)
					(width 0)
					(fill yes)
				)
			)
		)
	)
)
